(kicad_pcb
	(version 20260206)
	(generator "pcbnew")
	(generator_version "10.0")
	(general
		(thickness 1.6)
		(legacy_teardrops no)
	)
	(paper "A4")
	(title_block
		(title "04192023_DAF0TMB3IC0_F0TG_MB_C_brd_V02_OCP.brd")
		(comment 1 "Grand Teton / footprints 6850-6855 of 8354")
	)
	(layers
		(0 "F.Cu" signal "TOP")
		(4 "In1.Cu" signal "GND")
		(6 "In2.Cu" signal "IN1")
		(8 "In3.Cu" signal "GND1")
		(10 "In4.Cu" signal "IN2")
		(12 "In5.Cu" signal "GND2")
		(14 "In6.Cu" signal "IN3")
		(16 "In7.Cu" signal "GND3")
		(18 "In8.Cu" signal "VCC")
		(20 "In9.Cu" signal "VCC1")
		(22 "In10.Cu" signal "GND4")
		(24 "In11.Cu" signal "IN4")
		(26 "In12.Cu" signal "GND5")
		(28 "In13.Cu" signal "IN5")
		(30 "In14.Cu" signal "GND6")
		(32 "In15.Cu" signal "IN6")
		(34 "In16.Cu" signal "GND7")
		(2 "B.Cu" signal "BOTTOM")
		(9 "F.Adhes" user "F.Adhesive")
		(11 "B.Adhes" user "B.Adhesive")
		(13 "F.Paste" user "Package Geometry/Pastemask Top")
		(15 "B.Paste" user "Package Geometry/Pastemask Bottom")
		(5 "F.SilkS" user "Ref Des/Silkscreen Top")
		(7 "B.SilkS" user "Ref Des/Silkscreen Bottom")
		(1 "F.Mask" user "Board Geometry/Soldermask Top")
		(3 "B.Mask" user "Board Geometry/Soldermask Bottom")
		(17 "Dwgs.User" user "User.Drawings")
		(19 "Cmts.User" user "User.Comments")
		(21 "Eco1.User" user "User.Eco1")
		(23 "Eco2.User" user "User.Eco2")
		(25 "Edge.Cuts" user "Board Geometry/Outline")
		(27 "Margin" user)
		(31 "F.CrtYd" user "Package Geometry/Place Bound Top")
		(29 "B.CrtYd" user "Package Geometry/Place Bound Bottom")
		(35 "F.Fab" user "Ref Des/Assembly Top")
		(33 "B.Fab" user "Ref Des/Assembly Bottom")
	)
	(footprint ""
		(layer "B.Cu")
		(at 216.127076 -327.009252)
		(property "Reference" "R1267"
			(at 0 0 0)
			(layer "B.SilkS")
			(hide yes)
			(effects
				(font
					(size 1.27 1.27)
				)
				(justify mirror)
			)
		)
		(property "Value" ""
			(at 0 0 0)
			(layer "B.Fab")
			(effects
				(font
					(size 1.27 1.27)
				)
				(justify mirror)
			)
		)
		(duplicate_pad_numbers_are_jumpers no)
		(fp_line
			(start -0.7874 -0.4064)
			(end -0.7874 0.4064)
			(stroke
				(width 0.1524)
				(type default)
			)
			(layer "B.SilkS")
		)
		(fp_line
			(start -0.7874 0.4064)
			(end 0.7874 0.4064)
			(stroke
				(width 0.1524)
				(type default)
			)
			(layer "B.SilkS")
		)
		(fp_line
			(start 0.7874 -0.4064)
			(end -0.7874 -0.4064)
			(stroke
				(width 0.1524)
				(type default)
			)
			(layer "B.SilkS")
		)
		(fp_line
			(start 0.7874 0.4064)
			(end 0.7874 -0.4064)
			(stroke
				(width 0.1524)
				(type default)
			)
			(layer "B.SilkS")
		)
		(fp_line
			(start -0.67945 -0.3048)
			(end -0.67945 0.3048)
			(stroke
				(width 0.1)
				(type default)
			)
			(layer "B.Fab")
		)
		(fp_line
			(start -0.67945 0.3048)
			(end -0.120396 0.3048)
			(stroke
				(width 0.1)
				(type default)
			)
			(layer "B.Fab")
		)
		(fp_line
			(start -0.12065 -0.3048)
			(end -0.67945 -0.3048)
			(stroke
				(width 0.1)
				(type default)
			)
			(layer "B.Fab")
		)
		(fp_line
			(start -0.12065 -0.2794)
			(end -0.12065 -0.3048)
			(stroke
				(width 0.1)
				(type default)
			)
			(layer "B.Fab")
		)
		(fp_line
			(start -0.120396 0.2794)
			(end 0.12065 0.2794)
			(stroke
				(width 0.1)
				(type default)
			)
			(layer "B.Fab")
		)
		(fp_line
			(start -0.120396 0.3048)
			(end -0.120396 0.2794)
			(stroke
				(width 0.1)
				(type default)
			)
			(layer "B.Fab")
		)
		(fp_line
			(start 0.12065 -0.305054)
			(end 0.12065 -0.2794)
			(stroke
				(width 0.1)
				(type default)
			)
			(layer "B.Fab")
		)
		(fp_line
			(start 0.12065 -0.2794)
			(end -0.12065 -0.2794)
			(stroke
				(width 0.1)
				(type default)
			)
			(layer "B.Fab")
		)
		(fp_line
			(start 0.12065 0.2794)
			(end 0.12065 0.3048)
			(stroke
				(width 0.1)
				(type default)
			)
			(layer "B.Fab")
		)
		(fp_line
			(start 0.12065 0.3048)
			(end 0.67945 0.3048)
			(stroke
				(width 0.1)
				(type default)
			)
			(layer "B.Fab")
		)
		(fp_line
			(start 0.67945 -0.305054)
			(end 0.12065 -0.305054)
			(stroke
				(width 0.1)
				(type default)
			)
			(layer "B.Fab")
		)
		(fp_line
			(start 0.67945 0.3048)
			(end 0.67945 -0.305054)
			(stroke
				(width 0.1)
				(type default)
			)
			(layer "B.Fab")
		)
		(pad "1" smd circle
			(at 0.40005 0 180)
			(size 0 0)
			(layers "B.Cu" "B.Mask" "B.Paste")
			(net "P3V3_ADC128_2_VCC")
		)
		(pad "2" smd circle
			(at -0.40005 0 180)
			(size 0 0)
			(layers "B.Cu" "B.Mask" "B.Paste")
			(net "ADC128_2_VREF")
		)
	)
	(footprint ""
		(layer "B.Cu")
		(at 359.994454 -263.84631)
		(property "Reference" "C2648"
			(at 0 0 0)
			(layer "B.SilkS")
			(hide yes)
			(effects
				(font
					(size 1.27 1.27)
				)
				(justify mirror)
			)
		)
		(property "Value" ""
			(at 0 0 0)
			(layer "B.Fab")
			(effects
				(font
					(size 1.27 1.27)
				)
				(justify mirror)
			)
		)
		(duplicate_pad_numbers_are_jumpers no)
		(fp_line
			(start -0.7874 -0.4064)
			(end -0.7874 0.4064)
			(stroke
				(width 0.1524)
				(type default)
			)
			(layer "B.SilkS")
		)
		(fp_line
			(start -0.7874 0.4064)
			(end 0.7874 0.4064)
			(stroke
				(width 0.1524)
				(type default)
			)
			(layer "B.SilkS")
		)
		(fp_line
			(start 0.7874 -0.4064)
			(end -0.7874 -0.4064)
			(stroke
				(width 0.1524)
				(type default)
			)
			(layer "B.SilkS")
		)
		(fp_line
			(start 0.7874 0.4064)
			(end 0.7874 -0.4064)
			(stroke
				(width 0.1524)
				(type default)
			)
			(layer "B.SilkS")
		)
		(fp_line
			(start -0.67945 -0.3048)
			(end -0.67945 0.3048)
			(stroke
				(width 0.1)
				(type default)
			)
			(layer "B.Fab")
		)
		(fp_line
			(start -0.67945 0.3048)
			(end -0.120396 0.3048)
			(stroke
				(width 0.1)
				(type default)
			)
			(layer "B.Fab")
		)
		(fp_line
			(start -0.12065 -0.3048)
			(end -0.67945 -0.3048)
			(stroke
				(width 0.1)
				(type default)
			)
			(layer "B.Fab")
		)
		(fp_line
			(start -0.12065 -0.2794)
			(end -0.12065 -0.3048)
			(stroke
				(width 0.1)
				(type default)
			)
			(layer "B.Fab")
		)
		(fp_line
			(start -0.120396 0.2794)
			(end 0.12065 0.2794)
			(stroke
				(width 0.1)
				(type default)
			)
			(layer "B.Fab")
		)
		(fp_line
			(start -0.120396 0.3048)
			(end -0.120396 0.2794)
			(stroke
				(width 0.1)
				(type default)
			)
			(layer "B.Fab")
		)
		(fp_line
			(start 0.12065 -0.305054)
			(end 0.12065 -0.2794)
			(stroke
				(width 0.1)
				(type default)
			)
			(layer "B.Fab")
		)
		(fp_line
			(start 0.12065 -0.2794)
			(end -0.12065 -0.2794)
			(stroke
				(width 0.1)
				(type default)
			)
			(layer "B.Fab")
		)
		(fp_line
			(start 0.12065 0.2794)
			(end 0.12065 0.3048)
			(stroke
				(width 0.1)
				(type default)
			)
			(layer "B.Fab")
		)
		(fp_line
			(start 0.12065 0.3048)
			(end 0.67945 0.3048)
			(stroke
				(width 0.1)
				(type default)
			)
			(layer "B.Fab")
		)
		(fp_line
			(start 0.67945 -0.305054)
			(end 0.12065 -0.305054)
			(stroke
				(width 0.1)
				(type default)
			)
			(layer "B.Fab")
		)
		(fp_line
			(start 0.67945 0.3048)
			(end 0.67945 -0.305054)
			(stroke
				(width 0.1)
				(type default)
			)
			(layer "B.Fab")
		)
		(pad "1" smd circle
			(at 0.40005 0 180)
			(size 0 0)
			(layers "B.Cu" "B.Mask" "B.Paste")
			(net "PVDD11_S3_P0")
		)
		(pad "2" smd circle
			(at -0.40005 0 180)
			(size 0 0)
			(layers "B.Cu" "B.Mask" "B.Paste")
			(net "GND")
		)
	)
	(footprint ""
		(layer "B.Cu")
		(at 356.057454 -251.78131)
		(property "Reference" "C2589"
			(at 0 0 0)
			(layer "B.SilkS")
			(hide yes)
			(effects
				(font
					(size 1.27 1.27)
				)
				(justify mirror)
			)
		)
		(property "Value" ""
			(at 0 0 0)
			(layer "B.Fab")
			(effects
				(font
					(size 1.27 1.27)
				)
				(justify mirror)
			)
		)
		(duplicate_pad_numbers_are_jumpers no)
		(fp_line
			(start -0.7874 -0.4064)
			(end -0.7874 0.4064)
			(stroke
				(width 0.1524)
				(type default)
			)
			(layer "B.SilkS")
		)
		(fp_line
			(start -0.7874 0.4064)
			(end 0.7874 0.4064)
			(stroke
				(width 0.1524)
				(type default)
			)
			(layer "B.SilkS")
		)
		(fp_line
			(start 0.7874 -0.4064)
			(end -0.7874 -0.4064)
			(stroke
				(width 0.1524)
				(type default)
			)
			(layer "B.SilkS")
		)
		(fp_line
			(start 0.7874 0.4064)
			(end 0.7874 -0.4064)
			(stroke
				(width 0.1524)
				(type default)
			)
			(layer "B.SilkS")
		)
		(fp_line
			(start -0.67945 -0.3048)
			(end -0.67945 0.3048)
			(stroke
				(width 0.1)
				(type default)
			)
			(layer "B.Fab")
		)
		(fp_line
			(start -0.67945 0.3048)
			(end -0.120396 0.3048)
			(stroke
				(width 0.1)
				(type default)
			)
			(layer "B.Fab")
		)
		(fp_line
			(start -0.12065 -0.3048)
			(end -0.67945 -0.3048)
			(stroke
				(width 0.1)
				(type default)
			)
			(layer "B.Fab")
		)
		(fp_line
			(start -0.12065 -0.2794)
			(end -0.12065 -0.3048)
			(stroke
				(width 0.1)
				(type default)
			)
			(layer "B.Fab")
		)
		(fp_line
			(start -0.120396 0.2794)
			(end 0.12065 0.2794)
			(stroke
				(width 0.1)
				(type default)
			)
			(layer "B.Fab")
		)
		(fp_line
			(start -0.120396 0.3048)
			(end -0.120396 0.2794)
			(stroke
				(width 0.1)
				(type default)
			)
			(layer "B.Fab")
		)
		(fp_line
			(start 0.12065 -0.305054)
			(end 0.12065 -0.2794)
			(stroke
				(width 0.1)
				(type default)
			)
			(layer "B.Fab")
		)
		(fp_line
			(start 0.12065 -0.2794)
			(end -0.12065 -0.2794)
			(stroke
				(width 0.1)
				(type default)
			)
			(layer "B.Fab")
		)
		(fp_line
			(start 0.12065 0.2794)
			(end 0.12065 0.3048)
			(stroke
				(width 0.1)
				(type default)
			)
			(layer "B.Fab")
		)
		(fp_line
			(start 0.12065 0.3048)
			(end 0.67945 0.3048)
			(stroke
				(width 0.1)
				(type default)
			)
			(layer "B.Fab")
		)
		(fp_line
			(start 0.67945 -0.305054)
			(end 0.12065 -0.305054)
			(stroke
				(width 0.1)
				(type default)
			)
			(layer "B.Fab")
		)
		(fp_line
			(start 0.67945 0.3048)
			(end 0.67945 -0.305054)
			(stroke
				(width 0.1)
				(type default)
			)
			(layer "B.Fab")
		)
		(pad "1" smd circle
			(at 0.40005 0 180)
			(size 0 0)
			(layers "B.Cu" "B.Mask" "B.Paste")
			(net "PVDDCR_SOC_P0")
		)
		(pad "2" smd circle
			(at -0.40005 0 180)
			(size 0 0)
			(layers "B.Cu" "B.Mask" "B.Paste")
			(net "GND")
		)
	)
	(footprint ""
		(layer "B.Cu")
		(at 180.858922 -20.378166 90)
		(property "Reference" "R2420"
			(at 0 0 90)
			(layer "B.SilkS")
			(hide yes)
			(effects
				(font
					(size 1.27 1.27)
				)
				(justify mirror)
			)
		)
		(property "Value" ""
			(at 0 0 90)
			(layer "B.Fab")
			(effects
				(font
					(size 1.27 1.27)
				)
				(justify mirror)
			)
		)
		(duplicate_pad_numbers_are_jumpers no)
		(fp_line
			(start 0.7874 -0.4064)
			(end -0.7874 -0.4064)
			(stroke
				(width 0.1524)
				(type default)
			)
			(layer "B.SilkS")
		)
		(fp_line
			(start -0.7874 -0.4064)
			(end -0.7874 0.4064)
			(stroke
				(width 0.1524)
				(type default)
			)
			(layer "B.SilkS")
		)
		(fp_line
			(start 0.7874 0.4064)
			(end 0.7874 -0.4064)
			(stroke
				(width 0.1524)
				(type default)
			)
			(layer "B.SilkS")
		)
		(fp_line
			(start -0.7874 0.4064)
			(end 0.7874 0.4064)
			(stroke
				(width 0.1524)
				(type default)
			)
			(layer "B.SilkS")
		)
		(fp_line
			(start 0.67945 -0.305054)
			(end 0.12065 -0.305054)
			(stroke
				(width 0.1)
				(type default)
			)
			(layer "B.Fab")
		)
		(fp_line
			(start 0.12065 -0.305054)
			(end 0.12065 -0.2794)
			(stroke
				(width 0.1)
				(type default)
			)
			(layer "B.Fab")
		)
		(fp_line
			(start -0.12065 -0.3048)
			(end -0.67945 -0.3048)
			(stroke
				(width 0.1)
				(type default)
			)
			(layer "B.Fab")
		)
		(fp_line
			(start -0.67945 -0.3048)
			(end -0.67945 0.3048)
			(stroke
				(width 0.1)
				(type default)
			)
			(layer "B.Fab")
		)
		(fp_line
			(start 0.12065 -0.2794)
			(end -0.12065 -0.2794)
			(stroke
				(width 0.1)
				(type default)
			)
			(layer "B.Fab")
		)
		(fp_line
			(start -0.12065 -0.2794)
			(end -0.12065 -0.3048)
			(stroke
				(width 0.1)
				(type default)
			)
			(layer "B.Fab")
		)
		(fp_line
			(start 0.12065 0.2794)
			(end 0.12065 0.3048)
			(stroke
				(width 0.1)
				(type default)
			)
			(layer "B.Fab")
		)
		(fp_line
			(start -0.120396 0.2794)
			(end 0.12065 0.2794)
			(stroke
				(width 0.1)
				(type default)
			)
			(layer "B.Fab")
		)
		(fp_line
			(start 0.67945 0.3048)
			(end 0.67945 -0.305054)
			(stroke
				(width 0.1)
				(type default)
			)
			(layer "B.Fab")
		)
		(fp_line
			(start 0.12065 0.3048)
			(end 0.67945 0.3048)
			(stroke
				(width 0.1)
				(type default)
			)
			(layer "B.Fab")
		)
		(fp_line
			(start -0.120396 0.3048)
			(end -0.120396 0.2794)
			(stroke
				(width 0.1)
				(type default)
			)
			(layer "B.Fab")
		)
		(fp_line
			(start -0.67945 0.3048)
			(end -0.120396 0.3048)
			(stroke
				(width 0.1)
				(type default)
			)
			(layer "B.Fab")
		)
		(pad "1" smd circle
			(at 0.40005 0 270)
			(size 0 0)
			(layers "B.Cu" "B.Mask" "B.Paste")
			(net "SMB_CPU0_CPU1_APML_SDA")
		)
		(pad "2" smd circle
			(at -0.40005 0 270)
			(size 0 0)
			(layers "B.Cu" "B.Mask" "B.Paste")
			(net "SMB_CPU0_CPU1_APML_SDA_R")
		)
	)
	(footprint ""
		(layer "B.Cu")
		(at 215.2523 -402.744432 -90)
		(property "Reference" "PR3980"
			(at 0 0 90)
			(layer "B.SilkS")
			(hide yes)
			(effects
				(font
					(size 1.27 1.27)
				)
				(justify mirror)
			)
		)
		(property "Value" ""
			(at 0 0 90)
			(layer "B.Fab")
			(effects
				(font
					(size 1.27 1.27)
				)
				(justify mirror)
			)
		)
		(duplicate_pad_numbers_are_jumpers no)
		(fp_line
			(start -0.7874 0.4064)
			(end 0.7874 0.4064)
			(stroke
				(width 0.1524)
				(type default)
			)
			(layer "B.SilkS")
		)
		(fp_line
			(start 0.7874 0.4064)
			(end 0.7874 -0.4064)
			(stroke
				(width 0.1524)
				(type default)
			)
			(layer "B.SilkS")
		)
		(fp_line
			(start -0.7874 -0.4064)
			(end -0.7874 0.4064)
			(stroke
				(width 0.1524)
				(type default)
			)
			(layer "B.SilkS")
		)
		(fp_line
			(start 0.7874 -0.4064)
			(end -0.7874 -0.4064)
			(stroke
				(width 0.1524)
				(type default)
			)
			(layer "B.SilkS")
		)
		(fp_line
			(start -0.67945 0.3048)
			(end -0.120396 0.3048)
			(stroke
				(width 0.1)
				(type default)
			)
			(layer "B.Fab")
		)
		(fp_line
			(start -0.120396 0.3048)
			(end -0.120396 0.2794)
			(stroke
				(width 0.1)
				(type default)
			)
			(layer "B.Fab")
		)
		(fp_line
			(start 0.12065 0.3048)
			(end 0.67945 0.3048)
			(stroke
				(width 0.1)
				(type default)
			)
			(layer "B.Fab")
		)
		(fp_line
			(start 0.67945 0.3048)
			(end 0.67945 -0.305054)
			(stroke
				(width 0.1)
				(type default)
			)
			(layer "B.Fab")
		)
		(fp_line
			(start -0.120396 0.2794)
			(end 0.12065 0.2794)
			(stroke
				(width 0.1)
				(type default)
			)
			(layer "B.Fab")
		)
		(fp_line
			(start 0.12065 0.2794)
			(end 0.12065 0.3048)
			(stroke
				(width 0.1)
				(type default)
			)
			(layer "B.Fab")
		)
		(fp_line
			(start -0.12065 -0.2794)
			(end -0.12065 -0.3048)
			(stroke
				(width 0.1)
				(type default)
			)
			(layer "B.Fab")
		)
		(fp_line
			(start 0.12065 -0.2794)
			(end -0.12065 -0.2794)
			(stroke
				(width 0.1)
				(type default)
			)
			(layer "B.Fab")
		)
		(fp_line
			(start -0.67945 -0.3048)
			(end -0.67945 0.3048)
			(stroke
				(width 0.1)
				(type default)
			)
			(layer "B.Fab")
		)
		(fp_line
			(start -0.12065 -0.3048)
			(end -0.67945 -0.3048)
			(stroke
				(width 0.1)
				(type default)
			)
			(layer "B.Fab")
		)
		(fp_line
			(start 0.12065 -0.305054)
			(end 0.12065 -0.2794)
			(stroke
				(width 0.1)
				(type default)
			)
			(layer "B.Fab")
		)
		(fp_line
			(start 0.67945 -0.305054)
			(end 0.12065 -0.305054)
			(stroke
				(width 0.1)
				(type default)
			)
			(layer "B.Fab")
		)
		(pad "1" smd circle
			(at 0.40005 0 90)
			(size 0 0)
			(layers "B.Cu" "B.Mask" "B.Paste")
			(net "HSC_VDD_R_3")
		)
		(pad "2" smd circle
			(at -0.40005 0 90)
			(size 0 0)
			(layers "B.Cu" "B.Mask" "B.Paste")
			(net "HSC_VDD")
		)
	)
	(footprint ""
		(layer "B.Cu")
		(at 100.878386 -267.529564)
		(property "Reference" "C2360"
			(at 0 0 0)
			(layer "B.SilkS")
			(hide yes)
			(effects
				(font
					(size 1.27 1.27)
				)
				(justify mirror)
			)
		)
		(property "Value" ""
			(at 0 0 0)
			(layer "B.Fab")
			(effects
				(font
					(size 1.27 1.27)
				)
				(justify mirror)
			)
		)
		(duplicate_pad_numbers_are_jumpers no)
		(fp_line
			(start -0.7874 -0.4064)
			(end -0.7874 0.4064)
			(stroke
				(width 0.1524)
				(type default)
			)
			(layer "B.SilkS")
		)
		(fp_line
			(start -0.7874 0.4064)
			(end 0.7874 0.4064)
			(stroke
				(width 0.1524)
				(type default)
			)
			(layer "B.SilkS")
		)
		(fp_line
			(start 0.7874 -0.4064)
			(end -0.7874 -0.4064)
			(stroke
				(width 0.1524)
				(type default)
			)
			(layer "B.SilkS")
		)
		(fp_line
			(start 0.7874 0.4064)
			(end 0.7874 -0.4064)
			(stroke
				(width 0.1524)
				(type default)
			)
			(layer "B.SilkS")
		)
		(fp_line
			(start -0.67945 -0.3048)
			(end -0.67945 0.3048)
			(stroke
				(width 0.1)
				(type default)
			)
			(layer "B.Fab")
		)
		(fp_line
			(start -0.67945 0.3048)
			(end -0.120396 0.3048)
			(stroke
				(width 0.1)
				(type default)
			)
			(layer "B.Fab")
		)
		(fp_line
			(start -0.12065 -0.3048)
			(end -0.67945 -0.3048)
			(stroke
				(width 0.1)
				(type default)
			)
			(layer "B.Fab")
		)
		(fp_line
			(start -0.12065 -0.2794)
			(end -0.12065 -0.3048)
			(stroke
				(width 0.1)
				(type default)
			)
			(layer "B.Fab")
		)
		(fp_line
			(start -0.120396 0.2794)
			(end 0.12065 0.2794)
			(stroke
				(width 0.1)
				(type default)
			)
			(layer "B.Fab")
		)
		(fp_line
			(start -0.120396 0.3048)
			(end -0.120396 0.2794)
			(stroke
				(width 0.1)
				(type default)
			)
			(layer "B.Fab")
		)
		(fp_line
			(start 0.12065 -0.305054)
			(end 0.12065 -0.2794)
			(stroke
				(width 0.1)
				(type default)
			)
			(layer "B.Fab")
		)
		(fp_line
			(start 0.12065 -0.2794)
			(end -0.12065 -0.2794)
			(stroke
				(width 0.1)
				(type default)
			)
			(layer "B.Fab")
		)
		(fp_line
			(start 0.12065 0.2794)
			(end 0.12065 0.3048)
			(stroke
				(width 0.1)
				(type default)
			)
			(layer "B.Fab")
		)
		(fp_line
			(start 0.12065 0.3048)
			(end 0.67945 0.3048)
			(stroke
				(width 0.1)
				(type default)
			)
			(layer "B.Fab")
		)
		(fp_line
			(start 0.67945 -0.305054)
			(end 0.12065 -0.305054)
			(stroke
				(width 0.1)
				(type default)
			)
			(layer "B.Fab")
		)
		(fp_line
			(start 0.67945 0.3048)
			(end 0.67945 -0.305054)
			(stroke
				(width 0.1)
				(type default)
			)
			(layer "B.Fab")
		)
		(pad "1" smd circle
			(at 0.40005 0 180)
			(size 0 0)
			(layers "B.Cu" "B.Mask" "B.Paste")
			(net "PVDDCR_CPU1_P1")
		)
		(pad "2" smd circle
			(at -0.40005 0 180)
			(size 0 0)
			(layers "B.Cu" "B.Mask" "B.Paste")
			(net "GND")
		)
	)
)
